(kicad_pcb
	(version 20260206)
	(generator "pcbnew")
	(generator_version "10.0")
	(general
		(thickness 1.6)
		(legacy_teardrops no)
	)
	(paper "A4")
	(title_block
		(title "12092022_DA0F0TMDCD0_F0T_Management_Board_D_brd_V3_OCP.brd")
		(comment 1 "Grand Teton / footprints 1239-1244 of 1440")
	)
	(layers
		(0 "F.Cu" signal "TOP")
		(4 "In1.Cu" signal "GND")
		(6 "In2.Cu" signal "IN1")
		(8 "In3.Cu" signal "GND1")
		(10 "In4.Cu" signal "IN2")
		(12 "In5.Cu" signal "VCC")
		(14 "In6.Cu" signal "VCC1")
		(16 "In7.Cu" signal "IN3")
		(18 "In8.Cu" signal "GND2")
		(20 "In9.Cu" signal "IN4")
		(22 "In10.Cu" signal "GND3")
		(2 "B.Cu" signal "BOTTOM")
		(9 "F.Adhes" user "F.Adhesive")
		(11 "B.Adhes" user "B.Adhesive")
		(13 "F.Paste" user "Package Geometry/Pastemask Top")
		(15 "B.Paste" user "Package Geometry/Pastemask Bottom")
		(5 "F.SilkS" user "Ref Des/Silkscreen Top")
		(7 "B.SilkS" user "Ref Des/Silkscreen Bottom")
		(1 "F.Mask" user "Board Geometry/Soldermask Top")
		(3 "B.Mask" user "Board Geometry/Soldermask Bottom")
		(17 "Dwgs.User" user "User.Drawings")
		(19 "Cmts.User" user "User.Comments")
		(21 "Eco1.User" user "User.Eco1")
		(23 "Eco2.User" user "User.Eco2")
		(25 "Edge.Cuts" user "Board Geometry/Outline")
		(27 "Margin" user)
		(31 "F.CrtYd" user "Package Geometry/Place Bound Top")
		(29 "B.CrtYd" user "Package Geometry/Place Bound Bottom")
		(35 "F.Fab" user "Ref Des/Assembly Top")
		(33 "B.Fab" user "Ref Des/Assembly Bottom")
	)
	(footprint ""
		(layer "B.Cu")
		(at 72.621394 -72.047608 -90)
		(property "Reference" "R684"
			(at 0 0 90)
			(layer "B.SilkS")
			(hide yes)
			(effects
				(font
					(size 1.27 1.27)
				)
				(justify mirror)
			)
		)
		(property "Value" ""
			(at 0 0 90)
			(layer "B.Fab")
			(effects
				(font
					(size 1.27 1.27)
				)
				(justify mirror)
			)
		)
		(duplicate_pad_numbers_are_jumpers no)
		(fp_line
			(start -0.7874 0.4064)
			(end 0.7874 0.4064)
			(stroke
				(width 0.1524)
				(type default)
			)
			(layer "B.SilkS")
		)
		(fp_line
			(start 0.7874 0.4064)
			(end 0.7874 -0.4064)
			(stroke
				(width 0.1524)
				(type default)
			)
			(layer "B.SilkS")
		)
		(fp_line
			(start -0.7874 -0.4064)
			(end -0.7874 0.4064)
			(stroke
				(width 0.1524)
				(type default)
			)
			(layer "B.SilkS")
		)
		(fp_line
			(start 0.7874 -0.4064)
			(end -0.7874 -0.4064)
			(stroke
				(width 0.1524)
				(type default)
			)
			(layer "B.SilkS")
		)
		(fp_line
			(start -0.67945 0.3048)
			(end -0.120396 0.3048)
			(stroke
				(width 0.1)
				(type default)
			)
			(layer "B.Fab")
		)
		(fp_line
			(start -0.120396 0.3048)
			(end -0.120396 0.2794)
			(stroke
				(width 0.1)
				(type default)
			)
			(layer "B.Fab")
		)
		(fp_line
			(start 0.12065 0.3048)
			(end 0.67945 0.3048)
			(stroke
				(width 0.1)
				(type default)
			)
			(layer "B.Fab")
		)
		(fp_line
			(start 0.67945 0.3048)
			(end 0.67945 -0.305054)
			(stroke
				(width 0.1)
				(type default)
			)
			(layer "B.Fab")
		)
		(fp_line
			(start -0.120396 0.2794)
			(end 0.12065 0.2794)
			(stroke
				(width 0.1)
				(type default)
			)
			(layer "B.Fab")
		)
		(fp_line
			(start 0.12065 0.2794)
			(end 0.12065 0.3048)
			(stroke
				(width 0.1)
				(type default)
			)
			(layer "B.Fab")
		)
		(fp_line
			(start -0.12065 -0.2794)
			(end -0.12065 -0.3048)
			(stroke
				(width 0.1)
				(type default)
			)
			(layer "B.Fab")
		)
		(fp_line
			(start 0.12065 -0.2794)
			(end -0.12065 -0.2794)
			(stroke
				(width 0.1)
				(type default)
			)
			(layer "B.Fab")
		)
		(fp_line
			(start -0.67945 -0.3048)
			(end -0.67945 0.3048)
			(stroke
				(width 0.1)
				(type default)
			)
			(layer "B.Fab")
		)
		(fp_line
			(start -0.12065 -0.3048)
			(end -0.67945 -0.3048)
			(stroke
				(width 0.1)
				(type default)
			)
			(layer "B.Fab")
		)
		(fp_line
			(start 0.12065 -0.305054)
			(end 0.12065 -0.2794)
			(stroke
				(width 0.1)
				(type default)
			)
			(layer "B.Fab")
		)
		(fp_line
			(start 0.67945 -0.305054)
			(end 0.12065 -0.305054)
			(stroke
				(width 0.1)
				(type default)
			)
			(layer "B.Fab")
		)
		(pad "1" smd circle
			(at 0.40005 0 90)
			(size 0 0)
			(layers "B.Cu" "B.Mask" "B.Paste")
			(net "BMC_EMMC_WP_N")
		)
		(pad "2" smd circle
			(at -0.40005 0 90)
			(size 0 0)
			(layers "B.Cu" "B.Mask" "B.Paste")
			(net "GND")
		)
	)
	(footprint ""
		(layer "B.Cu")
		(at 44.38396 -34.637726 90)
		(property "Reference" "R139"
			(at 0 0 90)
			(layer "B.SilkS")
			(hide yes)
			(effects
				(font
					(size 1.27 1.27)
				)
				(justify mirror)
			)
		)
		(property "Value" ""
			(at 0 0 90)
			(layer "B.Fab")
			(effects
				(font
					(size 1.27 1.27)
				)
				(justify mirror)
			)
		)
		(duplicate_pad_numbers_are_jumpers no)
		(fp_line
			(start 0.7874 -0.4064)
			(end -0.7874 -0.4064)
			(stroke
				(width 0.1524)
				(type default)
			)
			(layer "B.SilkS")
		)
		(fp_line
			(start -0.7874 -0.4064)
			(end -0.7874 0.4064)
			(stroke
				(width 0.1524)
				(type default)
			)
			(layer "B.SilkS")
		)
		(fp_line
			(start 0.7874 0.4064)
			(end 0.7874 -0.4064)
			(stroke
				(width 0.1524)
				(type default)
			)
			(layer "B.SilkS")
		)
		(fp_line
			(start -0.7874 0.4064)
			(end 0.7874 0.4064)
			(stroke
				(width 0.1524)
				(type default)
			)
			(layer "B.SilkS")
		)
		(fp_line
			(start 0.67945 -0.305054)
			(end 0.12065 -0.305054)
			(stroke
				(width 0.1)
				(type default)
			)
			(layer "B.Fab")
		)
		(fp_line
			(start 0.12065 -0.305054)
			(end 0.12065 -0.2794)
			(stroke
				(width 0.1)
				(type default)
			)
			(layer "B.Fab")
		)
		(fp_line
			(start -0.12065 -0.3048)
			(end -0.67945 -0.3048)
			(stroke
				(width 0.1)
				(type default)
			)
			(layer "B.Fab")
		)
		(fp_line
			(start -0.67945 -0.3048)
			(end -0.67945 0.3048)
			(stroke
				(width 0.1)
				(type default)
			)
			(layer "B.Fab")
		)
		(fp_line
			(start 0.12065 -0.2794)
			(end -0.12065 -0.2794)
			(stroke
				(width 0.1)
				(type default)
			)
			(layer "B.Fab")
		)
		(fp_line
			(start -0.12065 -0.2794)
			(end -0.12065 -0.3048)
			(stroke
				(width 0.1)
				(type default)
			)
			(layer "B.Fab")
		)
		(fp_line
			(start 0.12065 0.2794)
			(end 0.12065 0.3048)
			(stroke
				(width 0.1)
				(type default)
			)
			(layer "B.Fab")
		)
		(fp_line
			(start -0.120396 0.2794)
			(end 0.12065 0.2794)
			(stroke
				(width 0.1)
				(type default)
			)
			(layer "B.Fab")
		)
		(fp_line
			(start 0.67945 0.3048)
			(end 0.67945 -0.305054)
			(stroke
				(width 0.1)
				(type default)
			)
			(layer "B.Fab")
		)
		(fp_line
			(start 0.12065 0.3048)
			(end 0.67945 0.3048)
			(stroke
				(width 0.1)
				(type default)
			)
			(layer "B.Fab")
		)
		(fp_line
			(start -0.120396 0.3048)
			(end -0.120396 0.2794)
			(stroke
				(width 0.1)
				(type default)
			)
			(layer "B.Fab")
		)
		(fp_line
			(start -0.67945 0.3048)
			(end -0.120396 0.3048)
			(stroke
				(width 0.1)
				(type default)
			)
			(layer "B.Fab")
		)
		(pad "1" smd circle
			(at 0.40005 0 270)
			(size 0 0)
			(layers "B.Cu" "B.Mask" "B.Paste")
			(net "SMB_BMC_MM4_R_SDA")
		)
		(pad "2" smd circle
			(at -0.40005 0 270)
			(size 0 0)
			(layers "B.Cu" "B.Mask" "B.Paste")
			(net "SMB_BMC_MM4_SDA")
		)
	)
	(footprint ""
		(layer "B.Cu")
		(at 17.272 -80.772 90)
		(property "Reference" "R272"
			(at 0 0 90)
			(layer "B.SilkS")
			(hide yes)
			(effects
				(font
					(size 1.27 1.27)
				)
				(justify mirror)
			)
		)
		(property "Value" ""
			(at 0 0 90)
			(layer "B.Fab")
			(effects
				(font
					(size 1.27 1.27)
				)
				(justify mirror)
			)
		)
		(duplicate_pad_numbers_are_jumpers no)
		(fp_line
			(start 0.7874 -0.4064)
			(end -0.7874 -0.4064)
			(stroke
				(width 0.1524)
				(type default)
			)
			(layer "B.SilkS")
		)
		(fp_line
			(start -0.7874 -0.4064)
			(end -0.7874 0.4064)
			(stroke
				(width 0.1524)
				(type default)
			)
			(layer "B.SilkS")
		)
		(fp_line
			(start 0.7874 0.4064)
			(end 0.7874 -0.4064)
			(stroke
				(width 0.1524)
				(type default)
			)
			(layer "B.SilkS")
		)
		(fp_line
			(start -0.7874 0.4064)
			(end 0.7874 0.4064)
			(stroke
				(width 0.1524)
				(type default)
			)
			(layer "B.SilkS")
		)
		(fp_line
			(start 0.67945 -0.305054)
			(end 0.12065 -0.305054)
			(stroke
				(width 0.1)
				(type default)
			)
			(layer "B.Fab")
		)
		(fp_line
			(start 0.12065 -0.305054)
			(end 0.12065 -0.2794)
			(stroke
				(width 0.1)
				(type default)
			)
			(layer "B.Fab")
		)
		(fp_line
			(start -0.12065 -0.3048)
			(end -0.67945 -0.3048)
			(stroke
				(width 0.1)
				(type default)
			)
			(layer "B.Fab")
		)
		(fp_line
			(start -0.67945 -0.3048)
			(end -0.67945 0.3048)
			(stroke
				(width 0.1)
				(type default)
			)
			(layer "B.Fab")
		)
		(fp_line
			(start 0.12065 -0.2794)
			(end -0.12065 -0.2794)
			(stroke
				(width 0.1)
				(type default)
			)
			(layer "B.Fab")
		)
		(fp_line
			(start -0.12065 -0.2794)
			(end -0.12065 -0.3048)
			(stroke
				(width 0.1)
				(type default)
			)
			(layer "B.Fab")
		)
		(fp_line
			(start 0.12065 0.2794)
			(end 0.12065 0.3048)
			(stroke
				(width 0.1)
				(type default)
			)
			(layer "B.Fab")
		)
		(fp_line
			(start -0.120396 0.2794)
			(end 0.12065 0.2794)
			(stroke
				(width 0.1)
				(type default)
			)
			(layer "B.Fab")
		)
		(fp_line
			(start 0.67945 0.3048)
			(end 0.67945 -0.305054)
			(stroke
				(width 0.1)
				(type default)
			)
			(layer "B.Fab")
		)
		(fp_line
			(start 0.12065 0.3048)
			(end 0.67945 0.3048)
			(stroke
				(width 0.1)
				(type default)
			)
			(layer "B.Fab")
		)
		(fp_line
			(start -0.120396 0.3048)
			(end -0.120396 0.2794)
			(stroke
				(width 0.1)
				(type default)
			)
			(layer "B.Fab")
		)
		(fp_line
			(start -0.67945 0.3048)
			(end -0.120396 0.3048)
			(stroke
				(width 0.1)
				(type default)
			)
			(layer "B.Fab")
		)
		(pad "1" smd circle
			(at 0.40005 0 270)
			(size 0 0)
			(layers "B.Cu" "B.Mask" "B.Paste")
			(net "SMB_BMC_MM16_R3_SCL")
		)
		(pad "2" smd circle
			(at -0.40005 0 270)
			(size 0 0)
			(layers "B.Cu" "B.Mask" "B.Paste")
			(net "SMB_BMC_MM16_R5_SCL")
		)
	)
	(footprint ""
		(layer "B.Cu")
		(at 83.8454 -30.5435 180)
		(property "Reference" "C125"
			(at 0 0 0)
			(layer "B.SilkS")
			(hide yes)
			(effects
				(font
					(size 1.27 1.27)
				)
				(justify mirror)
			)
		)
		(property "Value" ""
			(at 0 0 0)
			(layer "B.Fab")
			(effects
				(font
					(size 1.27 1.27)
				)
				(justify mirror)
			)
		)
		(duplicate_pad_numbers_are_jumpers no)
		(fp_line
			(start 1.2954 0.5842)
			(end 1.2954 -0.5842)
			(stroke
				(width 0.1524)
				(type default)
			)
			(layer "B.SilkS")
		)
		(fp_line
			(start 1.2954 -0.5842)
			(end -1.2954 -0.5842)
			(stroke
				(width 0.1524)
				(type default)
			)
			(layer "B.SilkS")
		)
		(fp_line
			(start 0 -0.5842)
			(end 0 0.5842)
			(stroke
				(width 0.1524)
				(type default)
			)
			(layer "B.SilkS")
		)
		(fp_line
			(start -1.2954 0.5842)
			(end 1.2954 0.5842)
			(stroke
				(width 0.1524)
				(type default)
			)
			(layer "B.SilkS")
		)
		(fp_line
			(start -1.2954 -0.5842)
			(end -1.2954 0.5842)
			(stroke
				(width 0.1524)
				(type default)
			)
			(layer "B.SilkS")
		)
		(fp_line
			(start 1.1938 0.4064)
			(end 1.1938 -0.4064)
			(stroke
				(width 0.1)
				(type default)
			)
			(layer "B.Fab")
		)
		(fp_line
			(start 1.1938 -0.4064)
			(end 0.8636 -0.4064)
			(stroke
				(width 0.1)
				(type default)
			)
			(layer "B.Fab")
		)
		(fp_line
			(start 0.8636 0.4572)
			(end 0.8636 0.4064)
			(stroke
				(width 0.1)
				(type default)
			)
			(layer "B.Fab")
		)
		(fp_line
			(start 0.8636 0.4064)
			(end 1.1938 0.4064)
			(stroke
				(width 0.1)
				(type default)
			)
			(layer "B.Fab")
		)
		(fp_line
			(start 0.8636 -0.4064)
			(end 0.8636 -0.4572)
			(stroke
				(width 0.1)
				(type default)
			)
			(layer "B.Fab")
		)
		(fp_line
			(start 0.8636 -0.4572)
			(end -0.8636 -0.4572)
			(stroke
				(width 0.1)
				(type default)
			)
			(layer "B.Fab")
		)
		(fp_line
			(start -0.8636 0.4572)
			(end 0.8636 0.4572)
			(stroke
				(width 0.1)
				(type default)
			)
			(layer "B.Fab")
		)
		(fp_line
			(start -0.8636 0.4064)
			(end -0.8636 0.4572)
			(stroke
				(width 0.1)
				(type default)
			)
			(layer "B.Fab")
		)
		(fp_line
			(start -0.8636 -0.4064)
			(end -1.1938 -0.4064)
			(stroke
				(width 0.1)
				(type default)
			)
			(layer "B.Fab")
		)
		(fp_line
			(start -0.8636 -0.4572)
			(end -0.8636 -0.4064)
			(stroke
				(width 0.1)
				(type default)
			)
			(layer "B.Fab")
		)
		(fp_line
			(start -1.1938 0.4064)
			(end -0.8636 0.4064)
			(stroke
				(width 0.1)
				(type default)
			)
			(layer "B.Fab")
		)
		(fp_line
			(start -1.1938 -0.4064)
			(end -1.1938 0.4064)
			(stroke
				(width 0.1)
				(type default)
			)
			(layer "B.Fab")
		)
		(pad "1" smd rect
			(at 0.7366 0 90)
			(size 0.7112 0.8128)
			(layers "B.Cu" "B.Mask" "B.Paste")
			(net "P3V3_AUX")
		)
		(pad "2" smd rect
			(at -0.7366 0 90)
			(size 0.7112 0.8128)
			(layers "B.Cu" "B.Mask" "B.Paste")
			(net "GND")
		)
	)
	(footprint ""
		(layer "B.Cu")
		(at 60.440316 -45.029628 -90)
		(property "Reference" "C105"
			(at 0 0 90)
			(layer "B.SilkS")
			(hide yes)
			(effects
				(font
					(size 1.27 1.27)
				)
				(justify mirror)
			)
		)
		(property "Value" ""
			(at 0 0 90)
			(layer "B.Fab")
			(effects
				(font
					(size 1.27 1.27)
				)
				(justify mirror)
			)
		)
		(duplicate_pad_numbers_are_jumpers no)
		(fp_line
			(start -0.7874 0.4064)
			(end 0.7874 0.4064)
			(stroke
				(width 0.1524)
				(type default)
			)
			(layer "B.SilkS")
		)
		(fp_line
			(start 0.7874 0.4064)
			(end 0.7874 -0.4064)
			(stroke
				(width 0.1524)
				(type default)
			)
			(layer "B.SilkS")
		)
		(fp_line
			(start -0.7874 -0.4064)
			(end -0.7874 0.4064)
			(stroke
				(width 0.1524)
				(type default)
			)
			(layer "B.SilkS")
		)
		(fp_line
			(start 0.7874 -0.4064)
			(end -0.7874 -0.4064)
			(stroke
				(width 0.1524)
				(type default)
			)
			(layer "B.SilkS")
		)
		(fp_line
			(start -0.67945 0.3048)
			(end -0.120396 0.3048)
			(stroke
				(width 0.1)
				(type default)
			)
			(layer "B.Fab")
		)
		(fp_line
			(start -0.120396 0.3048)
			(end -0.120396 0.2794)
			(stroke
				(width 0.1)
				(type default)
			)
			(layer "B.Fab")
		)
		(fp_line
			(start 0.12065 0.3048)
			(end 0.67945 0.3048)
			(stroke
				(width 0.1)
				(type default)
			)
			(layer "B.Fab")
		)
		(fp_line
			(start 0.67945 0.3048)
			(end 0.67945 -0.305054)
			(stroke
				(width 0.1)
				(type default)
			)
			(layer "B.Fab")
		)
		(fp_line
			(start -0.120396 0.2794)
			(end 0.12065 0.2794)
			(stroke
				(width 0.1)
				(type default)
			)
			(layer "B.Fab")
		)
		(fp_line
			(start 0.12065 0.2794)
			(end 0.12065 0.3048)
			(stroke
				(width 0.1)
				(type default)
			)
			(layer "B.Fab")
		)
		(fp_line
			(start -0.12065 -0.2794)
			(end -0.12065 -0.3048)
			(stroke
				(width 0.1)
				(type default)
			)
			(layer "B.Fab")
		)
		(fp_line
			(start 0.12065 -0.2794)
			(end -0.12065 -0.2794)
			(stroke
				(width 0.1)
				(type default)
			)
			(layer "B.Fab")
		)
		(fp_line
			(start -0.67945 -0.3048)
			(end -0.67945 0.3048)
			(stroke
				(width 0.1)
				(type default)
			)
			(layer "B.Fab")
		)
		(fp_line
			(start -0.12065 -0.3048)
			(end -0.67945 -0.3048)
			(stroke
				(width 0.1)
				(type default)
			)
			(layer "B.Fab")
		)
		(fp_line
			(start 0.12065 -0.305054)
			(end 0.12065 -0.2794)
			(stroke
				(width 0.1)
				(type default)
			)
			(layer "B.Fab")
		)
		(fp_line
			(start 0.67945 -0.305054)
			(end 0.12065 -0.305054)
			(stroke
				(width 0.1)
				(type default)
			)
			(layer "B.Fab")
		)
		(pad "1" smd circle
			(at 0.40005 0 90)
			(size 0 0)
			(layers "B.Cu" "B.Mask" "B.Paste")
			(net "P1V8_AUX")
		)
		(pad "2" smd circle
			(at -0.40005 0 90)
			(size 0 0)
			(layers "B.Cu" "B.Mask" "B.Paste")
			(net "GND")
		)
	)
	(footprint ""
		(layer "B.Cu")
		(at 54.736492 -43.358054 90)
		(property "Reference" "C65"
			(at 0 0 90)
			(layer "B.SilkS")
			(hide yes)
			(effects
				(font
					(size 1.27 1.27)
				)
				(justify mirror)
			)
		)
		(property "Value" ""
			(at 0 0 90)
			(layer "B.Fab")
			(effects
				(font
					(size 1.27 1.27)
				)
				(justify mirror)
			)
		)
		(duplicate_pad_numbers_are_jumpers no)
		(fp_line
			(start 0.7874 -0.4064)
			(end -0.7874 -0.4064)
			(stroke
				(width 0.1524)
				(type default)
			)
			(layer "B.SilkS")
		)
		(fp_line
			(start -0.7874 -0.4064)
			(end -0.7874 0.4064)
			(stroke
				(width 0.1524)
				(type default)
			)
			(layer "B.SilkS")
		)
		(fp_line
			(start 0.7874 0.4064)
			(end 0.7874 -0.4064)
			(stroke
				(width 0.1524)
				(type default)
			)
			(layer "B.SilkS")
		)
		(fp_line
			(start -0.7874 0.4064)
			(end 0.7874 0.4064)
			(stroke
				(width 0.1524)
				(type default)
			)
			(layer "B.SilkS")
		)
		(fp_line
			(start 0.67945 -0.305054)
			(end 0.12065 -0.305054)
			(stroke
				(width 0.1)
				(type default)
			)
			(layer "B.Fab")
		)
		(fp_line
			(start 0.12065 -0.305054)
			(end 0.12065 -0.2794)
			(stroke
				(width 0.1)
				(type default)
			)
			(layer "B.Fab")
		)
		(fp_line
			(start -0.12065 -0.3048)
			(end -0.67945 -0.3048)
			(stroke
				(width 0.1)
				(type default)
			)
			(layer "B.Fab")
		)
		(fp_line
			(start -0.67945 -0.3048)
			(end -0.67945 0.3048)
			(stroke
				(width 0.1)
				(type default)
			)
			(layer "B.Fab")
		)
		(fp_line
			(start 0.12065 -0.2794)
			(end -0.12065 -0.2794)
			(stroke
				(width 0.1)
				(type default)
			)
			(layer "B.Fab")
		)
		(fp_line
			(start -0.12065 -0.2794)
			(end -0.12065 -0.3048)
			(stroke
				(width 0.1)
				(type default)
			)
			(layer "B.Fab")
		)
		(fp_line
			(start 0.12065 0.2794)
			(end 0.12065 0.3048)
			(stroke
				(width 0.1)
				(type default)
			)
			(layer "B.Fab")
		)
		(fp_line
			(start -0.120396 0.2794)
			(end 0.12065 0.2794)
			(stroke
				(width 0.1)
				(type default)
			)
			(layer "B.Fab")
		)
		(fp_line
			(start 0.67945 0.3048)
			(end 0.67945 -0.305054)
			(stroke
				(width 0.1)
				(type default)
			)
			(layer "B.Fab")
		)
		(fp_line
			(start 0.12065 0.3048)
			(end 0.67945 0.3048)
			(stroke
				(width 0.1)
				(type default)
			)
			(layer "B.Fab")
		)
		(fp_line
			(start -0.120396 0.3048)
			(end -0.120396 0.2794)
			(stroke
				(width 0.1)
				(type default)
			)
			(layer "B.Fab")
		)
		(fp_line
			(start -0.67945 0.3048)
			(end -0.120396 0.3048)
			(stroke
				(width 0.1)
				(type default)
			)
			(layer "B.Fab")
		)
		(pad "1" smd circle
			(at 0.40005 0 270)
			(size 0 0)
			(layers "B.Cu" "B.Mask" "B.Paste")
			(net "P3V3_STBY_PLLAHVDD")
		)
		(pad "2" smd circle
			(at -0.40005 0 270)
			(size 0 0)
			(layers "B.Cu" "B.Mask" "B.Paste")
			(net "GND")
		)
	)
)
